# T6G (Grand Teton) — schematic netlist excerpt (pin names and nets, part order shuffled) for the footprints in the layout excerpt that follows; sources: Cadence DE-HDL packaged netlist, KiCad conversion of 04192023_DAF0TMB3IC0_F0TG_MB_C_brd_V02_OCP.brd

C970  Q_CAP  4.7UF 6.3V 20% X6S  pkg 0402  page 301 : A = P0V9_CPU0_RT2_2A ; B = GND
PC157_6  Q_CAP  22UF 16V 20% X6S  pkg C0805  page 196 : A = SW_P12V_AUX_PVDDCR_CPU0_P0_FLT ; B = GND

(kicad_pcb
	(version 20260206)
	(generator "pcbnew")
	(generator_version "10.0")
	(general
		(thickness 1.6)
		(legacy_teardrops no)
	)
	(paper "A4")
	(title_block
		(title "04192023_DAF0TMB3IC0_F0TG_MB_C_brd_V02_OCP.brd")
		(comment 1 "Grand Teton / footprints 7755-7756 of 8354")
	)
	(layers
		(0 "F.Cu" signal "TOP")
		(4 "In1.Cu" signal "GND")
		(6 "In2.Cu" signal "IN1")
		(8 "In3.Cu" signal "GND1")
		(10 "In4.Cu" signal "IN2")
		(12 "In5.Cu" signal "GND2")
		(14 "In6.Cu" signal "IN3")
		(16 "In7.Cu" signal "GND3")
		(18 "In8.Cu" signal "VCC")
		(20 "In9.Cu" signal "VCC1")
		(22 "In10.Cu" signal "GND4")
		(24 "In11.Cu" signal "IN4")
		(26 "In12.Cu" signal "GND5")
		(28 "In13.Cu" signal "IN5")
		(30 "In14.Cu" signal "GND6")
		(32 "In15.Cu" signal "IN6")
		(34 "In16.Cu" signal "GND7")
		(2 "B.Cu" signal "BOTTOM")
		(9 "F.Adhes" user "F.Adhesive")
		(11 "B.Adhes" user "B.Adhesive")
		(13 "F.Paste" user "Package Geometry/Pastemask Top")
		(15 "B.Paste" user "Package Geometry/Pastemask Bottom")
		(5 "F.SilkS" user "Ref Des/Silkscreen Top")
		(7 "B.SilkS" user "Ref Des/Silkscreen Bottom")
		(1 "F.Mask" user "Board Geometry/Soldermask Top")
		(3 "B.Mask" user "Board Geometry/Soldermask Bottom")
		(17 "Dwgs.User" user "User.Drawings")
		(19 "Cmts.User" user "User.Comments")
		(21 "Eco1.User" user "User.Eco1")
		(23 "Eco2.User" user "User.Eco2")
		(25 "Edge.Cuts" user "Board Geometry/Outline")
		(27 "Margin" user)
		(31 "F.CrtYd" user "Package Geometry/Place Bound Top")
		(29 "B.CrtYd" user "Package Geometry/Place Bound Bottom")
		(35 "F.Fab" user "Ref Des/Assembly Top")
		(33 "B.Fab" user "Ref Des/Assembly Bottom")
	)
	(footprint ""
		(layer "B.Cu")
		(at 402.11502 -399.722848 -90)
		(property "Reference" "C970"
			(at 0 0 90)
			(layer "B.SilkS")
			(hide yes)
			(effects
				(font
					(size 1.27 1.27)
				)
				(justify mirror)
			)
		)
		(property "Value" ""
			(at 0 0 90)
			(layer "B.Fab")
			(effects
				(font
					(size 1.27 1.27)
				)
				(justify mirror)
			)
		)
		(duplicate_pad_numbers_are_jumpers no)
		(fp_line
			(start -0.7874 0.4064)
			(end 0.7874 0.4064)
			(stroke
				(width 0.1524)
				(type default)
			)
			(layer "B.SilkS")
		)
		(fp_line
			(start 0.7874 0.4064)
			(end 0.7874 -0.4064)
			(stroke
				(width 0.1524)
				(type default)
			)
			(layer "B.SilkS")
		)
		(fp_line
			(start -0.7874 -0.4064)
			(end -0.7874 0.4064)
			(stroke
				(width 0.1524)
				(type default)
			)
			(layer "B.SilkS")
		)
		(fp_line
			(start 0.7874 -0.4064)
			(end -0.7874 -0.4064)
			(stroke
				(width 0.1524)
				(type default)
			)
			(layer "B.SilkS")
		)
		(fp_line
			(start -0.67945 0.3048)
			(end -0.120396 0.3048)
			(stroke
				(width 0.1)
				(type default)
			)
			(layer "B.Fab")
		)
		(fp_line
			(start -0.120396 0.3048)
			(end -0.120396 0.2794)
			(stroke
				(width 0.1)
				(type default)
			)
			(layer "B.Fab")
		)
		(fp_line
			(start 0.12065 0.3048)
			(end 0.67945 0.3048)
			(stroke
				(width 0.1)
				(type default)
			)
			(layer "B.Fab")
		)
		(fp_line
			(start 0.67945 0.3048)
			(end 0.67945 -0.305054)
			(stroke
				(width 0.1)
				(type default)
			)
			(layer "B.Fab")
		)
		(fp_line
			(start -0.120396 0.2794)
			(end 0.12065 0.2794)
			(stroke
				(width 0.1)
				(type default)
			)
			(layer "B.Fab")
		)
		(fp_line
			(start 0.12065 0.2794)
			(end 0.12065 0.3048)
			(stroke
				(width 0.1)
				(type default)
			)
			(layer "B.Fab")
		)
		(fp_line
			(start -0.12065 -0.2794)
			(end -0.12065 -0.3048)
			(stroke
				(width 0.1)
				(type default)
			)
			(layer "B.Fab")
		)
		(fp_line
			(start 0.12065 -0.2794)
			(end -0.12065 -0.2794)
			(stroke
				(width 0.1)
				(type default)
			)
			(layer "B.Fab")
		)
		(fp_line
			(start -0.67945 -0.3048)
			(end -0.67945 0.3048)
			(stroke
				(width 0.1)
				(type default)
			)
			(layer "B.Fab")
		)
		(fp_line
			(start -0.12065 -0.3048)
			(end -0.67945 -0.3048)
			(stroke
				(width 0.1)
				(type default)
			)
			(layer "B.Fab")
		)
		(fp_line
			(start 0.12065 -0.305054)
			(end 0.12065 -0.2794)
			(stroke
				(width 0.1)
				(type default)
			)
			(layer "B.Fab")
		)
		(fp_line
			(start 0.67945 -0.305054)
			(end 0.12065 -0.305054)
			(stroke
				(width 0.1)
				(type default)
			)
			(layer "B.Fab")
		)
		(pad "1" smd circle
			(at 0.40005 0 90)
			(size 0 0)
			(layers "B.Cu" "B.Mask" "B.Paste")
			(net "P0V9_CPU0_RT2_2A")
		)
		(pad "2" smd circle
			(at -0.40005 0 90)
			(size 0 0)
			(layers "B.Cu" "B.Mask" "B.Paste")
			(net "GND")
		)
	)
	(footprint ""
		(layer "B.Cu")
		(at 346.464636 -157.37586 90)
		(property "Reference" "PC157_6"
			(at 0 0 90)
			(layer "B.SilkS")
			(hide yes)
			(effects
				(font
					(size 1.27 1.27)
				)
				(justify mirror)
			)
		)
		(property "Value" ""
			(at 0 0 90)
			(layer "B.Fab")
			(effects
				(font
					(size 1.27 1.27)
				)
				(justify mirror)
			)
		)
		(duplicate_pad_numbers_are_jumpers no)
		(fp_line
			(start 1.524 -0.762)
			(end -1.524 -0.762)
			(stroke
				(width 0.1524)
				(type default)
			)
			(layer "B.SilkS")
		)
		(fp_line
			(start -1.524 -0.762)
			(end -1.524 0.762)
			(stroke
				(width 0.1524)
				(type default)
			)
			(layer "B.SilkS")
		)
		(fp_line
			(start 1.524 0.762)
			(end 1.524 -0.762)
			(stroke
				(width 0.1524)
				(type default)
			)
			(layer "B.SilkS")
		)
		(fp_line
			(start -1.524 0.762)
			(end 1.524 0.762)
			(stroke
				(width 0.1524)
				(type default)
			)
			(layer "B.SilkS")
		)
		(fp_line
			(start 1.1049 -0.724916)
			(end 1.1049 0.724916)
			(stroke
				(width 0.1)
				(type default)
			)
			(layer "B.Fab")
		)
		(fp_line
			(start -1.1049 -0.724916)
			(end 1.1049 -0.724916)
			(stroke
				(width 0.1)
				(type default)
			)
			(layer "B.Fab")
		)
		(fp_line
			(start 1.1049 0.724916)
			(end -1.1049 0.724916)
			(stroke
				(width 0.1)
				(type default)
			)
			(layer "B.Fab")
		)
		(fp_line
			(start -1.1049 0.724916)
			(end -1.1049 -0.724916)
			(stroke
				(width 0.1)
				(type default)
			)
			(layer "B.Fab")
		)
		(pad "1" smd rect
			(at 0.889 0 90)
			(size 1.016 1.27)
			(layers "B.Cu" "B.Mask" "B.Paste")
			(net "SW_P12V_AUX_PVDDCR_CPU0_P0_FLT")
		)
		(pad "2" smd rect
			(at -0.889 0 90)
			(size 1.016 1.27)
			(layers "B.Cu" "B.Mask" "B.Paste")
			(net "GND")
		)
	)
)
